(kicad_pcb
	(version 20260206)
	(generator "pcbnew")
	(generator_version "10.0")
	(general
		(thickness 1.6)
		(legacy_teardrops no)
	)
	(paper "A4")
	(title_block
		(title "01162023_DA0F0TEBIF0_F0T_Expander_BD_F_brd_V02_OCP.brd")
		(comment 1 "Grand Teton / footprints 1861-1868 of 9728")
	)
	(layers
		(0 "F.Cu" signal "TOP")
		(4 "In1.Cu" signal "GND")
		(6 "In2.Cu" signal "VCC")
		(8 "In3.Cu" signal "VCC1")
		(10 "In4.Cu" signal "GND1")
		(12 "In5.Cu" signal "IN1")
		(14 "In6.Cu" signal "GND2")
		(16 "In7.Cu" signal "IN2")
		(18 "In8.Cu" signal "GND3")
		(20 "In9.Cu" signal "IN3")
		(22 "In10.Cu" signal "GND4")
		(24 "In11.Cu" signal "IN4")
		(26 "In12.Cu" signal "GND5")
		(28 "In13.Cu" signal "IN5")
		(30 "In14.Cu" signal "GND6")
		(32 "In15.Cu" signal "IN6")
		(34 "In16.Cu" signal "GND7")
		(2 "B.Cu" signal "BOTTOM")
		(9 "F.Adhes" user "F.Adhesive")
		(11 "B.Adhes" user "B.Adhesive")
		(13 "F.Paste" user "Package Geometry/Pastemask Top")
		(15 "B.Paste" user "Package Geometry/Pastemask Bottom")
		(5 "F.SilkS" user "Ref Des/Silkscreen Top")
		(7 "B.SilkS" user "Ref Des/Silkscreen Bottom")
		(1 "F.Mask" user "Board Geometry/Soldermask Top")
		(3 "B.Mask" user "Board Geometry/Soldermask Bottom")
		(17 "Dwgs.User" user "User.Drawings")
		(19 "Cmts.User" user "User.Comments")
		(21 "Eco1.User" user "User.Eco1")
		(23 "Eco2.User" user "User.Eco2")
		(25 "Edge.Cuts" user "Board Geometry/Outline")
		(27 "Margin" user)
		(31 "F.CrtYd" user "Package Geometry/Place Bound Top")
		(29 "B.CrtYd" user "Package Geometry/Place Bound Bottom")
		(35 "F.Fab" user "Ref Des/Assembly Top")
		(33 "B.Fab" user "Ref Des/Assembly Bottom")
	)
	(footprint ""
		(layer "F.Cu")
		(at 315.101732 -32.849312 90)
		(property "Reference" "R5690"
			(at 0 0 90)
			(layer "F.SilkS")
			(hide yes)
			(effects
				(font
					(size 1.27 1.27)
				)
			)
		)
		(property "Value" ""
			(at 0 0 90)
			(layer "F.Fab")
			(effects
				(font
					(size 1.27 1.27)
				)
			)
		)
		(duplicate_pad_numbers_are_jumpers no)
		(fp_line
			(start 0.7874 -0.4064)
			(end 0.7874 0.4064)
			(stroke
				(width 0.1524)
				(type default)
			)
			(layer "F.SilkS")
		)
		(fp_line
			(start -0.7874 -0.4064)
			(end 0.7874 -0.4064)
			(stroke
				(width 0.1524)
				(type default)
			)
			(layer "F.SilkS")
		)
		(fp_line
			(start 0.7874 0.4064)
			(end -0.7874 0.4064)
			(stroke
				(width 0.1524)
				(type default)
			)
			(layer "F.SilkS")
		)
		(fp_line
			(start -0.7874 0.4064)
			(end -0.7874 -0.4064)
			(stroke
				(width 0.1524)
				(type default)
			)
			(layer "F.SilkS")
		)
		(fp_line
			(start -0.12065 -0.305054)
			(end -0.12065 -0.2794)
			(stroke
				(width 0.1)
				(type default)
			)
			(layer "F.Fab")
		)
		(fp_line
			(start -0.67945 -0.305054)
			(end -0.12065 -0.305054)
			(stroke
				(width 0.1)
				(type default)
			)
			(layer "F.Fab")
		)
		(fp_line
			(start 0.67945 -0.3048)
			(end 0.67945 0.3048)
			(stroke
				(width 0.1)
				(type default)
			)
			(layer "F.Fab")
		)
		(fp_line
			(start 0.12065 -0.3048)
			(end 0.67945 -0.3048)
			(stroke
				(width 0.1)
				(type default)
			)
			(layer "F.Fab")
		)
		(fp_line
			(start 0.12065 -0.2794)
			(end 0.12065 -0.3048)
			(stroke
				(width 0.1)
				(type default)
			)
			(layer "F.Fab")
		)
		(fp_line
			(start -0.12065 -0.2794)
			(end 0.12065 -0.2794)
			(stroke
				(width 0.1)
				(type default)
			)
			(layer "F.Fab")
		)
		(fp_line
			(start 0.120396 0.2794)
			(end -0.12065 0.2794)
			(stroke
				(width 0.1)
				(type default)
			)
			(layer "F.Fab")
		)
		(fp_line
			(start -0.12065 0.2794)
			(end -0.12065 0.3048)
			(stroke
				(width 0.1)
				(type default)
			)
			(layer "F.Fab")
		)
		(fp_line
			(start 0.67945 0.3048)
			(end 0.120396 0.3048)
			(stroke
				(width 0.1)
				(type default)
			)
			(layer "F.Fab")
		)
		(fp_line
			(start 0.120396 0.3048)
			(end 0.120396 0.2794)
			(stroke
				(width 0.1)
				(type default)
			)
			(layer "F.Fab")
		)
		(fp_line
			(start -0.12065 0.3048)
			(end -0.67945 0.3048)
			(stroke
				(width 0.1)
				(type default)
			)
			(layer "F.Fab")
		)
		(fp_line
			(start -0.67945 0.3048)
			(end -0.67945 -0.305054)
			(stroke
				(width 0.1)
				(type default)
			)
			(layer "F.Fab")
		)
		(pad "1" smd circle
			(at -0.40005 0 90)
			(size 0 0)
			(layers "F.Cu" "F.Mask" "F.Paste")
			(net "RST_SMB_SSD11_ISO_R_N")
		)
		(pad "2" smd circle
			(at 0.40005 0 90)
			(size 0 0)
			(layers "F.Cu" "F.Mask" "F.Paste")
			(net "RST_SMB_SSD11_ISO_N")
		)
	)
	(footprint ""
		(layer "F.Cu")
		(at 470.416128 -521.354304 180)
		(property "Reference" "J60_12"
			(at -2.8448 -1.402334 0)
			(unlocked yes)
			(layer "B.SilkS")
			(effects
				(font
					(size 0.7874 0.5842)
					(thickness 0.1524)
				)
				(justify mirror)
			)
		)
		(property "Value" ""
			(at 0 0 180)
			(layer "F.Fab")
			(effects
				(font
					(size 1.27 1.27)
				)
			)
		)
		(duplicate_pad_numbers_are_jumpers no)
		(pad "1" thru_hole circle
			(at 0 0 180)
			(size 0.4572 0.4572)
			(drill 0.2032)
			(layers "*.Cu" "*.Mask")
			(remove_unused_layers no)
			(net "Net_584")
			(clearance 0.127)
			(thermal_gap 0.127)
			(padstack
				(mode front_inner_back)
				(layer "Inner"
					(shape circle)
					(size 0.4572 0.4572)
					(clearance 0.127)
				)
				(layer "B.Cu"
					(shape circle)
					(size 0.508 0.508)
					(clearance 0.1016)
				)
			)
		)
	)
	(footprint ""
		(layer "F.Cu")
		(at 80.454754 -22.961346 90)
		(property "Reference" "R1645"
			(at 0 0 90)
			(layer "F.SilkS")
			(hide yes)
			(effects
				(font
					(size 1.27 1.27)
				)
			)
		)
		(property "Value" ""
			(at 0 0 90)
			(layer "F.Fab")
			(effects
				(font
					(size 1.27 1.27)
				)
			)
		)
		(duplicate_pad_numbers_are_jumpers no)
		(fp_line
			(start 0.7874 -0.4064)
			(end 0.7874 0.4064)
			(stroke
				(width 0.1524)
				(type default)
			)
			(layer "F.SilkS")
		)
		(fp_line
			(start -0.7874 -0.4064)
			(end 0.7874 -0.4064)
			(stroke
				(width 0.1524)
				(type default)
			)
			(layer "F.SilkS")
		)
		(fp_line
			(start 0.7874 0.4064)
			(end -0.7874 0.4064)
			(stroke
				(width 0.1524)
				(type default)
			)
			(layer "F.SilkS")
		)
		(fp_line
			(start -0.7874 0.4064)
			(end -0.7874 -0.4064)
			(stroke
				(width 0.1524)
				(type default)
			)
			(layer "F.SilkS")
		)
		(fp_line
			(start -0.12065 -0.305054)
			(end -0.12065 -0.2794)
			(stroke
				(width 0.1)
				(type default)
			)
			(layer "F.Fab")
		)
		(fp_line
			(start -0.67945 -0.305054)
			(end -0.12065 -0.305054)
			(stroke
				(width 0.1)
				(type default)
			)
			(layer "F.Fab")
		)
		(fp_line
			(start 0.67945 -0.3048)
			(end 0.67945 0.3048)
			(stroke
				(width 0.1)
				(type default)
			)
			(layer "F.Fab")
		)
		(fp_line
			(start 0.12065 -0.3048)
			(end 0.67945 -0.3048)
			(stroke
				(width 0.1)
				(type default)
			)
			(layer "F.Fab")
		)
		(fp_line
			(start 0.12065 -0.2794)
			(end 0.12065 -0.3048)
			(stroke
				(width 0.1)
				(type default)
			)
			(layer "F.Fab")
		)
		(fp_line
			(start -0.12065 -0.2794)
			(end 0.12065 -0.2794)
			(stroke
				(width 0.1)
				(type default)
			)
			(layer "F.Fab")
		)
		(fp_line
			(start 0.120396 0.2794)
			(end -0.12065 0.2794)
			(stroke
				(width 0.1)
				(type default)
			)
			(layer "F.Fab")
		)
		(fp_line
			(start -0.12065 0.2794)
			(end -0.12065 0.3048)
			(stroke
				(width 0.1)
				(type default)
			)
			(layer "F.Fab")
		)
		(fp_line
			(start 0.67945 0.3048)
			(end 0.120396 0.3048)
			(stroke
				(width 0.1)
				(type default)
			)
			(layer "F.Fab")
		)
		(fp_line
			(start 0.120396 0.3048)
			(end 0.120396 0.2794)
			(stroke
				(width 0.1)
				(type default)
			)
			(layer "F.Fab")
		)
		(fp_line
			(start -0.12065 0.3048)
			(end -0.67945 0.3048)
			(stroke
				(width 0.1)
				(type default)
			)
			(layer "F.Fab")
		)
		(fp_line
			(start -0.67945 0.3048)
			(end -0.67945 -0.305054)
			(stroke
				(width 0.1)
				(type default)
			)
			(layer "F.Fab")
		)
		(pad "1" smd circle
			(at -0.40005 0 90)
			(size 0 0)
			(layers "F.Cu" "F.Mask" "F.Paste")
			(net "SMB_SSD2_ISO_EN")
		)
		(pad "2" smd circle
			(at 0.40005 0 90)
			(size 0 0)
			(layers "F.Cu" "F.Mask" "F.Paste")
			(net "P3V3_AUX")
		)
	)
	(footprint ""
		(layer "F.Cu")
		(at 47.287688 -356.244906 90)
		(property "Reference" "C163"
			(at 0 0 90)
			(layer "F.SilkS")
			(hide yes)
			(effects
				(font
					(size 1.27 1.27)
				)
			)
		)
		(property "Value" ""
			(at 0 0 90)
			(layer "F.Fab")
			(effects
				(font
					(size 1.27 1.27)
				)
			)
		)
		(duplicate_pad_numbers_are_jumpers no)
		(fp_line
			(start 0.299974 -0.150114)
			(end 0.299974 0.150114)
			(stroke
				(width 0.1)
				(type default)
			)
			(layer "F.Fab")
		)
		(fp_line
			(start -0.299974 -0.150114)
			(end 0.299974 -0.150114)
			(stroke
				(width 0.1)
				(type default)
			)
			(layer "F.Fab")
		)
		(fp_line
			(start 0.299974 0.150114)
			(end -0.299974 0.150114)
			(stroke
				(width 0.1)
				(type default)
			)
			(layer "F.Fab")
		)
		(fp_line
			(start -0.299974 0.150114)
			(end -0.299974 -0.150114)
			(stroke
				(width 0.1)
				(type default)
			)
			(layer "F.Fab")
		)
		(pad "1" smd rect
			(at -0.2667 0 90)
			(size 0.3048 0.381)
			(layers "F.Cu" "F.Mask" "F.Paste")
			(net "P5E_PEX0_STN7_TX_DP<126>")
		)
		(pad "2" smd rect
			(at 0.2667 0 90)
			(size 0.3048 0.381)
			(layers "F.Cu" "F.Mask" "F.Paste")
			(net "P5E_PEX0_STN7_TX_C_DP<126>")
		)
	)
	(footprint ""
		(layer "F.Cu")
		(at 367.022634 -44.341542 90)
		(property "Reference" "R646"
			(at 0 0 90)
			(layer "F.SilkS")
			(hide yes)
			(effects
				(font
					(size 1.27 1.27)
				)
			)
		)
		(property "Value" ""
			(at 0 0 90)
			(layer "F.Fab")
			(effects
				(font
					(size 1.27 1.27)
				)
			)
		)
		(duplicate_pad_numbers_are_jumpers no)
		(fp_line
			(start 0.7874 -0.4064)
			(end 0.7874 0.4064)
			(stroke
				(width 0.1524)
				(type default)
			)
			(layer "F.SilkS")
		)
		(fp_line
			(start -0.7874 -0.4064)
			(end 0.7874 -0.4064)
			(stroke
				(width 0.1524)
				(type default)
			)
			(layer "F.SilkS")
		)
		(fp_line
			(start 0.7874 0.4064)
			(end -0.7874 0.4064)
			(stroke
				(width 0.1524)
				(type default)
			)
			(layer "F.SilkS")
		)
		(fp_line
			(start -0.7874 0.4064)
			(end -0.7874 -0.4064)
			(stroke
				(width 0.1524)
				(type default)
			)
			(layer "F.SilkS")
		)
		(fp_line
			(start -0.12065 -0.305054)
			(end -0.12065 -0.2794)
			(stroke
				(width 0.1)
				(type default)
			)
			(layer "F.Fab")
		)
		(fp_line
			(start -0.67945 -0.305054)
			(end -0.12065 -0.305054)
			(stroke
				(width 0.1)
				(type default)
			)
			(layer "F.Fab")
		)
		(fp_line
			(start 0.67945 -0.3048)
			(end 0.67945 0.3048)
			(stroke
				(width 0.1)
				(type default)
			)
			(layer "F.Fab")
		)
		(fp_line
			(start 0.12065 -0.3048)
			(end 0.67945 -0.3048)
			(stroke
				(width 0.1)
				(type default)
			)
			(layer "F.Fab")
		)
		(fp_line
			(start 0.12065 -0.2794)
			(end 0.12065 -0.3048)
			(stroke
				(width 0.1)
				(type default)
			)
			(layer "F.Fab")
		)
		(fp_line
			(start -0.12065 -0.2794)
			(end 0.12065 -0.2794)
			(stroke
				(width 0.1)
				(type default)
			)
			(layer "F.Fab")
		)
		(fp_line
			(start 0.120396 0.2794)
			(end -0.12065 0.2794)
			(stroke
				(width 0.1)
				(type default)
			)
			(layer "F.Fab")
		)
		(fp_line
			(start -0.12065 0.2794)
			(end -0.12065 0.3048)
			(stroke
				(width 0.1)
				(type default)
			)
			(layer "F.Fab")
		)
		(fp_line
			(start 0.67945 0.3048)
			(end 0.120396 0.3048)
			(stroke
				(width 0.1)
				(type default)
			)
			(layer "F.Fab")
		)
		(fp_line
			(start 0.120396 0.3048)
			(end 0.120396 0.2794)
			(stroke
				(width 0.1)
				(type default)
			)
			(layer "F.Fab")
		)
		(fp_line
			(start -0.12065 0.3048)
			(end -0.67945 0.3048)
			(stroke
				(width 0.1)
				(type default)
			)
			(layer "F.Fab")
		)
		(fp_line
			(start -0.67945 0.3048)
			(end -0.67945 -0.305054)
			(stroke
				(width 0.1)
				(type default)
			)
			(layer "F.Fab")
		)
		(pad "1" smd circle
			(at -0.40005 0 90)
			(size 0 0)
			(layers "F.Cu" "F.Mask" "F.Paste")
			(net "P12V_SSD12")
		)
		(pad "2" smd circle
			(at 0.40005 0 90)
			(size 0 0)
			(layers "F.Cu" "F.Mask" "F.Paste")
			(net "P12V_SSD12_VIN_N")
		)
	)
	(footprint ""
		(layer "F.Cu")
		(at 420.555166 -35.876738)
		(property "Reference" "R6117"
			(at 0 0 0)
			(layer "F.SilkS")
			(hide yes)
			(effects
				(font
					(size 1.27 1.27)
				)
			)
		)
		(property "Value" ""
			(at 0 0 0)
			(layer "F.Fab")
			(effects
				(font
					(size 1.27 1.27)
				)
			)
		)
		(duplicate_pad_numbers_are_jumpers no)
		(fp_line
			(start -0.7874 -0.4064)
			(end 0.7874 -0.4064)
			(stroke
				(width 0.1524)
				(type default)
			)
			(layer "F.SilkS")
		)
		(fp_line
			(start -0.7874 0.4064)
			(end -0.7874 -0.4064)
			(stroke
				(width 0.1524)
				(type default)
			)
			(layer "F.SilkS")
		)
		(fp_line
			(start 0.7874 -0.4064)
			(end 0.7874 0.4064)
			(stroke
				(width 0.1524)
				(type default)
			)
			(layer "F.SilkS")
		)
		(fp_line
			(start 0.7874 0.4064)
			(end -0.7874 0.4064)
			(stroke
				(width 0.1524)
				(type default)
			)
			(layer "F.SilkS")
		)
		(fp_line
			(start -0.67945 -0.305054)
			(end -0.12065 -0.305054)
			(stroke
				(width 0.1)
				(type default)
			)
			(layer "F.Fab")
		)
		(fp_line
			(start -0.67945 0.3048)
			(end -0.67945 -0.305054)
			(stroke
				(width 0.1)
				(type default)
			)
			(layer "F.Fab")
		)
		(fp_line
			(start -0.12065 -0.305054)
			(end -0.12065 -0.2794)
			(stroke
				(width 0.1)
				(type default)
			)
			(layer "F.Fab")
		)
		(fp_line
			(start -0.12065 -0.2794)
			(end 0.12065 -0.2794)
			(stroke
				(width 0.1)
				(type default)
			)
			(layer "F.Fab")
		)
		(fp_line
			(start -0.12065 0.2794)
			(end -0.12065 0.3048)
			(stroke
				(width 0.1)
				(type default)
			)
			(layer "F.Fab")
		)
		(fp_line
			(start -0.12065 0.3048)
			(end -0.67945 0.3048)
			(stroke
				(width 0.1)
				(type default)
			)
			(layer "F.Fab")
		)
		(fp_line
			(start 0.120396 0.2794)
			(end -0.12065 0.2794)
			(stroke
				(width 0.1)
				(type default)
			)
			(layer "F.Fab")
		)
		(fp_line
			(start 0.120396 0.3048)
			(end 0.120396 0.2794)
			(stroke
				(width 0.1)
				(type default)
			)
			(layer "F.Fab")
		)
		(fp_line
			(start 0.12065 -0.3048)
			(end 0.67945 -0.3048)
			(stroke
				(width 0.1)
				(type default)
			)
			(layer "F.Fab")
		)
		(fp_line
			(start 0.12065 -0.2794)
			(end 0.12065 -0.3048)
			(stroke
				(width 0.1)
				(type default)
			)
			(layer "F.Fab")
		)
		(fp_line
			(start 0.67945 -0.3048)
			(end 0.67945 0.3048)
			(stroke
				(width 0.1)
				(type default)
			)
			(layer "F.Fab")
		)
		(fp_line
			(start 0.67945 0.3048)
			(end 0.120396 0.3048)
			(stroke
				(width 0.1)
				(type default)
			)
			(layer "F.Fab")
		)
		(pad "1" smd circle
			(at -0.40005 0)
			(size 0 0)
			(layers "F.Cu" "F.Mask" "F.Paste")
			(net "P3V3_AUX")
		)
		(pad "2" smd circle
			(at 0.40005 0)
			(size 0 0)
			(layers "F.Cu" "F.Mask" "F.Paste")
			(net "PWRGD_P3V3_SSD15_D")
		)
	)
	(footprint ""
		(layer "F.Cu")
		(at 39.280592 -107.403138)
		(property "Reference" "C56"
			(at 0 0 0)
			(layer "F.SilkS")
			(hide yes)
			(effects
				(font
					(size 1.27 1.27)
				)
			)
		)
		(property "Value" ""
			(at 0 0 0)
			(layer "F.Fab")
			(effects
				(font
					(size 1.27 1.27)
				)
			)
		)
		(duplicate_pad_numbers_are_jumpers no)
		(fp_line
			(start -0.299974 -0.150114)
			(end 0.299974 -0.150114)
			(stroke
				(width 0.1)
				(type default)
			)
			(layer "F.Fab")
		)
		(fp_line
			(start -0.299974 0.150114)
			(end -0.299974 -0.150114)
			(stroke
				(width 0.1)
				(type default)
			)
			(layer "F.Fab")
		)
		(fp_line
			(start 0.299974 -0.150114)
			(end 0.299974 0.150114)
			(stroke
				(width 0.1)
				(type default)
			)
			(layer "F.Fab")
		)
		(fp_line
			(start 0.299974 0.150114)
			(end -0.299974 0.150114)
			(stroke
				(width 0.1)
				(type default)
			)
			(layer "F.Fab")
		)
		(pad "1" smd rect
			(at -0.2667 0)
			(size 0.3048 0.381)
			(layers "F.Cu" "F.Mask" "F.Paste")
			(net "P5E_PEX0_STN1_TX_DN<20>")
		)
		(pad "2" smd rect
			(at 0.2667 0)
			(size 0.3048 0.381)
			(layers "F.Cu" "F.Mask" "F.Paste")
			(net "P5E_PEX0_STN1_TX_C_DN<20>")
		)
	)
	(footprint ""
		(layer "F.Cu")
		(at 303.726596 -55.418228 90)
		(property "Reference" "PC428"
			(at 0 0 90)
			(layer "F.SilkS")
			(hide yes)
			(effects
				(font
					(size 1.27 1.27)
				)
			)
		)
		(property "Value" ""
			(at 0 0 90)
			(layer "F.Fab")
			(effects
				(font
					(size 1.27 1.27)
				)
			)
		)
		(duplicate_pad_numbers_are_jumpers no)
		(fp_line
			(start 0.7874 -0.4064)
			(end 0.7874 0.4064)
			(stroke
				(width 0.1524)
				(type default)
			)
			(layer "F.SilkS")
		)
		(fp_line
			(start -0.7874 -0.4064)
			(end 0.7874 -0.4064)
			(stroke
				(width 0.1524)
				(type default)
			)
			(layer "F.SilkS")
		)
		(fp_line
			(start 0.7874 0.4064)
			(end -0.7874 0.4064)
			(stroke
				(width 0.1524)
				(type default)
			)
			(layer "F.SilkS")
		)
		(fp_line
			(start -0.7874 0.4064)
			(end -0.7874 -0.4064)
			(stroke
				(width 0.1524)
				(type default)
			)
			(layer "F.SilkS")
		)
		(fp_line
			(start -0.12065 -0.305054)
			(end -0.12065 -0.2794)
			(stroke
				(width 0.1)
				(type default)
			)
			(layer "F.Fab")
		)
		(fp_line
			(start -0.67945 -0.305054)
			(end -0.12065 -0.305054)
			(stroke
				(width 0.1)
				(type default)
			)
			(layer "F.Fab")
		)
		(fp_line
			(start 0.67945 -0.3048)
			(end 0.67945 0.3048)
			(stroke
				(width 0.1)
				(type default)
			)
			(layer "F.Fab")
		)
		(fp_line
			(start 0.12065 -0.3048)
			(end 0.67945 -0.3048)
			(stroke
				(width 0.1)
				(type default)
			)
			(layer "F.Fab")
		)
		(fp_line
			(start 0.12065 -0.2794)
			(end 0.12065 -0.3048)
			(stroke
				(width 0.1)
				(type default)
			)
			(layer "F.Fab")
		)
		(fp_line
			(start -0.12065 -0.2794)
			(end 0.12065 -0.2794)
			(stroke
				(width 0.1)
				(type default)
			)
			(layer "F.Fab")
		)
		(fp_line
			(start 0.120396 0.2794)
			(end -0.12065 0.2794)
			(stroke
				(width 0.1)
				(type default)
			)
			(layer "F.Fab")
		)
		(fp_line
			(start -0.12065 0.2794)
			(end -0.12065 0.3048)
			(stroke
				(width 0.1)
				(type default)
			)
			(layer "F.Fab")
		)
		(fp_line
			(start 0.67945 0.3048)
			(end 0.120396 0.3048)
			(stroke
				(width 0.1)
				(type default)
			)
			(layer "F.Fab")
		)
		(fp_line
			(start 0.120396 0.3048)
			(end 0.120396 0.2794)
			(stroke
				(width 0.1)
				(type default)
			)
			(layer "F.Fab")
		)
		(fp_line
			(start -0.12065 0.3048)
			(end -0.67945 0.3048)
			(stroke
				(width 0.1)
				(type default)
			)
			(layer "F.Fab")
		)
		(fp_line
			(start -0.67945 0.3048)
			(end -0.67945 -0.305054)
			(stroke
				(width 0.1)
				(type default)
			)
			(layer "F.Fab")
		)
		(pad "1" smd circle
			(at -0.40005 0 90)
			(size 0 0)
			(layers "F.Cu" "F.Mask" "F.Paste")
			(net "P12V_SSD10_R")
		)
		(pad "2" smd circle
			(at 0.40005 0 90)
			(size 0 0)
			(layers "F.Cu" "F.Mask" "F.Paste")
			(net "GND")
		)
	)
)
